# BASEBOARD_FAB2 (Tioga Pass) — schematic netlist excerpt (pin names and nets, part order shuffled) for the footprints in the layout excerpt that follows; sources: Cadence DE-HDL packaged netlist, KiCad conversion of Wiwynn_Tioga_Pass_MB.brd

EU4D2  NB3W1200L  IC  pkg LCC  page 102
  VDDA  = P3V3_DB1200_A
  GNDA  = GND
  NC(0)  = NC
  \100m_133m_n\  = FM_100M_N
  HBW_BYPASS_LOBW_N  = FM_HBW_BYPASS_LOWBW_N
  PWRGD_PWRDN_N  = FM_DB1200_PWRGD_R
  GND(0)  = GND
  VDDR  = P3V3_DB1200_R
  CLK_INP  = CLK_100M_DB1200_DP
  CLK_INN  = CLK_100M_DB1200_DN
  SA_0  = FM_DB1200_SMB_SA0
  SDA  = SMB_HOST_STBY_LVC3_SDA_R2
  SCL  = SMB_HOST_STBY_LVC3_SCL_R2
  SA_1  = FM_DB1200_SMB_SA1
  NC(2)  = NC
  NC(1)  = NC
  DIF_0P  = CLK_100M_CPU0_BCLK0_R_DP
  DIF_0N  = CLK_100M_CPU0_BCLK0_R_DN
  OE_0_N  = FM_DB1200ZL_BCLKS_EN_N
  OE_1_N  = FM_DB1200ZL_BCLKS_EN_N
  DIF_1P  = CLK_100M_CPU0_BCLK1_R_DP
  DIF_1N  = CLK_100M_CPU0_BCLK1_R_DN
  GND(1)  = GND
  VDD(0)  = P3V3_DB1200
  VDDIO(0)  = P3V3_DB1200
  DIF_2P  = CLK_100M_CPU0_BCLK2_R_DP
  DIF_2N  = CLK_100M_CPU0_BCLK2_R_DN
  OE_2_N  = FM_DB1200ZL_BCLKS_EN_N
  OE_3_N  = FM_CPU0_MCP_CLK_EN_N
  DIF_3P  = CLK_100M_CPU0_PE_REFCLK_R_DP
  DIF_3N  = CLK_100M_CPU0_PE_REFCLK_R_DN
  VDDIO(1)  = P3V3_DB1200
  GND(2)  = GND
  DIF_4P  = CLK_100M_CPU0_RC_REFCLK0_R_DP
  DIF_4N  = CLK_100M_CPU0_RC_REFCLK0_R_DN
  OE_4_N  = FM_CPU0_MCP_CLK_EN_N
  OE_5_N  = FM_CPU0_MCP_CLK_EN_N
  DIF_5P  = CLK_100M_CPU0_RC_REFCLK1_R_DP
  DIF_5N  = CLK_100M_CPU0_RC_REFCLK1_R_DN
  VDD(1)  = P3V3_DB1200
  GND(3)  = GND
  DIF_6P  = CLK_100M_CPU1_BCLK0_R_DP
  DIF_6N  = CLK_100M_CPU1_BCLK0_R_DN
  OE_6_N  = FM_DB1200ZL_BCLKS_EN_N
  OE_7_N  = FM_DB1200ZL_BCLKS_EN_N
  DIF_7P  = CLK_100M_CPU1_BCLK1_R_DP
  DIF_7N  = CLK_100M_CPU1_BCLK1_R_DN
  GND(4)  = GND
  VDDIO(2)  = P3V3_DB1200
  DIF_8P  = CLK_100M_CPU1_BCLK2_R_DP
  DIF_8N  = CLK_100M_CPU1_BCLK2_R_DN
  OE_8_N  = FM_DB1200ZL_BCLKS_EN_N
  OE_9_N  = FM_CPU1_MCP_CLK_EN_N
  DIF_9P  = CLK_100M_CPU1_PE_REFCLK_R_DP
  DIF_9N  = CLK_100M_CPU1_PE_REFCLK_R_DN
  VDDIO(3)  = P3V3_DB1200
  VDD(2)  = P3V3_DB1200
  GND(5)  = GND
  DIF_10P  = CLK_100M_CPU1_RC_REFCLK0_R_DP
  DIF_10N  = CLK_100M_CPU1_RC_REFCLK0_R_DN
  OE_10_N  = FM_CPU1_MCP_CLK_EN_N
  OE_11_N  = FM_CPU1_MCP_CLK_EN_N
  DIF_11P  = CLK_100M_CPU1_RC_REFCLK1_R_DP
  DIF_11N  = CLK_100M_CPU1_RC_REFCLK1_R_DN
  THPAD  = GND

(kicad_pcb
	(version 20260206)
	(generator "pcbnew")
	(generator_version "10.0")
	(general
		(thickness 1.6)
		(legacy_teardrops no)
	)
	(paper "A4")
	(title_block
		(title "Wiwynn_Tioga_Pass_MB.brd")
		(comment 1 "Tioga Pass / footprint 752 of 4770 (EU4D2), pads 52-65 of 65")
	)
	(layers
		(0 "F.Cu" signal "TOP")
		(4 "In1.Cu" signal "L2GND")
		(6 "In2.Cu" signal "L3")
		(8 "In3.Cu" signal "L4GND")
		(10 "In4.Cu" signal "L5")
		(12 "In5.Cu" signal "L6GND")
		(14 "In6.Cu" signal "L7VCC")
		(16 "In7.Cu" signal "L8VCC")
		(18 "In8.Cu" signal "L9GND")
		(20 "In9.Cu" signal "L10")
		(22 "In10.Cu" signal "L11GND")
		(24 "In11.Cu" signal "L12")
		(26 "In12.Cu" signal "L13GND")
		(2 "B.Cu" signal "BOTTOM")
		(9 "F.Adhes" user "F.Adhesive")
		(11 "B.Adhes" user "B.Adhesive")
		(13 "F.Paste" user "Package Geometry/Pastemask Top")
		(15 "B.Paste" user "Package Geometry/Pastemask Bottom")
		(5 "F.SilkS" user "Ref Des/Silkscreen Top")
		(7 "B.SilkS" user "Ref Des/Silkscreen Bottom")
		(1 "F.Mask" user "Board Geometry/Soldermask Top")
		(3 "B.Mask" user "Board Geometry/Soldermask Bottom")
		(17 "Dwgs.User" user "User.Drawings")
		(19 "Cmts.User" user "User.Comments")
		(21 "Eco1.User" user "User.Eco1")
		(23 "Eco2.User" user "User.Eco2")
		(25 "Edge.Cuts" user "Board Geometry/Outline")
		(27 "Margin" user)
		(31 "F.CrtYd" user "Package Geometry/Place Bound Top")
		(29 "B.CrtYd" user "Package Geometry/Place Bound Bottom")
		(35 "F.Fab" user "Ref Des/Assembly Top")
		(33 "B.Fab" user "Ref Des/Assembly Bottom")
	)
	(footprint ""
		(layer "F.Cu")
		(at 169.422826 -80.961992 90)
		(property "Reference" "EU4D2"
			(at -8.471662 1.773174 0)
			(unlocked yes)
			(layer "F.SilkS")
			(effects
				(font
					(size 0.7874 0.5842)
					(thickness 0.1524)
				)
				(justify left)
			)
		)
		(property "Value" ""
			(at 0 0 90)
			(layer "F.Fab")
			(effects
				(font
					(size 1.27 1.27)
				)
			)
		)
		(duplicate_pad_numbers_are_jumpers no)
		(pad "52" smd custom
			(at 2.250694 -4.3688 90)
			(size 0.0762 0.0762)
			(layers "F.Cu" "F.Mask" "F.Paste")
			(net "FM_DB1200ZL_BCLKS_EN_N")
			(options
				(clearance outline)
				(anchor circle)
			)
			(primitives
				(gr_poly
					(pts
						(xy 0.1524 -0.381)
						(arc
							(start 0.1524 0.2286)
							(mid 0 0.381)
							(end -0.1524 0.2286)
						)
						(xy -0.1524 -0.381)
					)
					(width 0)
					(fill yes)
				)
			)
		)
		(pad "53" smd custom
			(at 1.750568 -4.3688 90)
			(size 0.0762 0.0762)
			(layers "F.Cu" "F.Mask" "F.Paste")
			(net "FM_CPU1_MCP_CLK_EN_N")
			(options
				(clearance outline)
				(anchor circle)
			)
			(primitives
				(gr_poly
					(pts
						(xy 0.1524 -0.381)
						(arc
							(start 0.1524 0.2286)
							(mid 0 0.381)
							(end -0.1524 0.2286)
						)
						(xy -0.1524 -0.381)
					)
					(width 0)
					(fill yes)
				)
			)
		)
		(pad "54" smd custom
			(at 1.250442 -4.3688 90)
			(size 0.0762 0.0762)
			(layers "F.Cu" "F.Mask" "F.Paste")
			(net "CLK_100M_CPU1_PE_REFCLK_R_DP")
			(options
				(clearance outline)
				(anchor circle)
			)
			(primitives
				(gr_poly
					(pts
						(xy 0.1524 -0.381)
						(arc
							(start 0.1524 0.2286)
							(mid 0 0.381)
							(end -0.1524 0.2286)
						)
						(xy -0.1524 -0.381)
					)
					(width 0)
					(fill yes)
				)
			)
		)
		(pad "55" smd custom
			(at 0.750316 -4.3688 90)
			(size 0.0762 0.0762)
			(layers "F.Cu" "F.Mask" "F.Paste")
			(net "CLK_100M_CPU1_PE_REFCLK_R_DN")
			(options
				(clearance outline)
				(anchor circle)
			)
			(primitives
				(gr_poly
					(pts
						(xy 0.1524 -0.381)
						(arc
							(start 0.1524 0.2286)
							(mid 0 0.381)
							(end -0.1524 0.2286)
						)
						(xy -0.1524 -0.381)
					)
					(width 0)
					(fill yes)
				)
			)
		)
		(pad "56" smd custom
			(at 0.25019 -4.3688 90)
			(size 0.0762 0.0762)
			(layers "F.Cu" "F.Mask" "F.Paste")
			(net "P3V3_DB1200")
			(options
				(clearance outline)
				(anchor circle)
			)
			(primitives
				(gr_poly
					(pts
						(xy 0.1524 -0.381)
						(arc
							(start 0.1524 0.2286)
							(mid 0 0.381)
							(end -0.1524 0.2286)
						)
						(xy -0.1524 -0.381)
					)
					(width 0)
					(fill yes)
				)
			)
		)
		(pad "57" smd custom
			(at -0.249936 -4.3688 90)
			(size 0.0762 0.0762)
			(layers "F.Cu" "F.Mask" "F.Paste")
			(net "P3V3_DB1200")
			(options
				(clearance outline)
				(anchor circle)
			)
			(primitives
				(gr_poly
					(pts
						(xy 0.1524 -0.381)
						(arc
							(start 0.1524 0.2286)
							(mid 0 0.381)
							(end -0.1524 0.2286)
						)
						(xy -0.1524 -0.381)
					)
					(width 0)
					(fill yes)
				)
			)
		)
		(pad "58" smd custom
			(at -0.750062 -4.3688 90)
			(size 0.0762 0.0762)
			(layers "F.Cu" "F.Mask" "F.Paste")
			(net "GND")
			(options
				(clearance outline)
				(anchor circle)
			)
			(primitives
				(gr_poly
					(pts
						(xy 0.1524 -0.381)
						(arc
							(start 0.1524 0.2286)
							(mid 0 0.381)
							(end -0.1524 0.2286)
						)
						(xy -0.1524 -0.381)
					)
					(width 0)
					(fill yes)
				)
			)
		)
		(pad "59" smd custom
			(at -1.250188 -4.3688 90)
			(size 0.0762 0.0762)
			(layers "F.Cu" "F.Mask" "F.Paste")
			(net "CLK_100M_CPU1_RC_REFCLK0_R_DP")
			(options
				(clearance outline)
				(anchor circle)
			)
			(primitives
				(gr_poly
					(pts
						(xy 0.1524 -0.381)
						(arc
							(start 0.1524 0.2286)
							(mid 0 0.381)
							(end -0.1524 0.2286)
						)
						(xy -0.1524 -0.381)
					)
					(width 0)
					(fill yes)
				)
			)
		)
		(pad "60" smd custom
			(at -1.750314 -4.3688 90)
			(size 0.0762 0.0762)
			(layers "F.Cu" "F.Mask" "F.Paste")
			(net "CLK_100M_CPU1_RC_REFCLK0_R_DN")
			(options
				(clearance outline)
				(anchor circle)
			)
			(primitives
				(gr_poly
					(pts
						(xy 0.1524 -0.381)
						(arc
							(start 0.1524 0.2286)
							(mid 0 0.381)
							(end -0.1524 0.2286)
						)
						(xy -0.1524 -0.381)
					)
					(width 0)
					(fill yes)
				)
			)
		)
		(pad "61" smd custom
			(at -2.25044 -4.3688 90)
			(size 0.0762 0.0762)
			(layers "F.Cu" "F.Mask" "F.Paste")
			(net "FM_CPU1_MCP_CLK_EN_N")
			(options
				(clearance outline)
				(anchor circle)
			)
			(primitives
				(gr_poly
					(pts
						(xy 0.1524 -0.381)
						(arc
							(start 0.1524 0.2286)
							(mid 0 0.381)
							(end -0.1524 0.2286)
						)
						(xy -0.1524 -0.381)
					)
					(width 0)
					(fill yes)
				)
			)
		)
		(pad "62" smd custom
			(at -2.750566 -4.3688 90)
			(size 0.0762 0.0762)
			(layers "F.Cu" "F.Mask" "F.Paste")
			(net "FM_CPU1_MCP_CLK_EN_N")
			(options
				(clearance outline)
				(anchor circle)
			)
			(primitives
				(gr_poly
					(pts
						(xy 0.1524 -0.381)
						(arc
							(start 0.1524 0.2286)
							(mid 0 0.381)
							(end -0.1524 0.2286)
						)
						(xy -0.1524 -0.381)
					)
					(width 0)
					(fill yes)
				)
			)
		)
		(pad "63" smd custom
			(at -3.250692 -4.3688 90)
			(size 0.0762 0.0762)
			(layers "F.Cu" "F.Mask" "F.Paste")
			(net "CLK_100M_CPU1_RC_REFCLK1_R_DP")
			(options
				(clearance outline)
				(anchor circle)
			)
			(primitives
				(gr_poly
					(pts
						(xy 0.1524 -0.381)
						(arc
							(start 0.1524 0.2286)
							(mid 0 0.381)
							(end -0.1524 0.2286)
						)
						(xy -0.1524 -0.381)
					)
					(width 0)
					(fill yes)
				)
			)
		)
		(pad "64" smd custom
			(at -3.750818 -4.3688 90)
			(size 0.0762 0.0762)
			(layers "F.Cu" "F.Mask" "F.Paste")
			(net "CLK_100M_CPU1_RC_REFCLK1_R_DN")
			(options
				(clearance outline)
				(anchor circle)
			)
			(primitives
				(gr_poly
					(pts
						(xy 0.1524 -0.381)
						(arc
							(start 0.1524 0.2286)
							(mid 0 0.381)
							(end -0.1524 0.2286)
						)
						(xy -0.1524 -0.381)
					)
					(width 0)
					(fill yes)
				)
			)
		)
		(pad "65" smd rect
			(at 0 0 90)
			(size 6.2484 6.2484)
			(layers "F.Cu" "F.Mask" "F.Paste")
			(net "GND")
		)
	)
)
